# S9S_MB_2U (Grand Teton) — schematic netlist excerpt (pin names and nets, part order shuffled) for the footprints in the layout excerpt that follows; sources: Cadence DE-HDL packaged netlist, KiCad conversion of 03242023_DA0F0TMBIJ0_F0T_Motherboard_J_brd_V01_OCP.brd

C1032  Q_CAP  22UF 4V 20% X6S  pkg C0402  page 74 : A = PVCCIN_CPU0 ; B = GND
C1769  Q_CAP  0.1UF 25V 10% X7R  pkg 0402  page 151 : A = P3V3_AUX ; B = GND

(kicad_pcb
	(version 20260206)
	(generator "pcbnew")
	(generator_version "10.0")
	(general
		(thickness 1.6)
		(legacy_teardrops no)
	)
	(paper "A4")
	(title_block
		(title "03242023_DA0F0TMBIJ0_F0T_Motherboard_J_brd_V01_OCP.brd")
		(comment 1 "Grand Teton / footprints 2122-2123 of 6105")
	)
	(layers
		(0 "F.Cu" signal "TOP")
		(4 "In1.Cu" signal "GND")
		(6 "In2.Cu" signal "IN1")
		(8 "In3.Cu" signal "GND1")
		(10 "In4.Cu" signal "IN2")
		(12 "In5.Cu" signal "GND2")
		(14 "In6.Cu" signal "IN3")
		(16 "In7.Cu" signal "GND3")
		(18 "In8.Cu" signal "VCC")
		(20 "In9.Cu" signal "VCC1")
		(22 "In10.Cu" signal "GND4")
		(24 "In11.Cu" signal "IN4")
		(26 "In12.Cu" signal "GND5")
		(28 "In13.Cu" signal "IN5")
		(30 "In14.Cu" signal "GND6")
		(32 "In15.Cu" signal "IN6")
		(34 "In16.Cu" signal "GND7")
		(2 "B.Cu" signal "BOTTOM")
		(9 "F.Adhes" user "F.Adhesive")
		(11 "B.Adhes" user "B.Adhesive")
		(13 "F.Paste" user "Package Geometry/Pastemask Top")
		(15 "B.Paste" user "Package Geometry/Pastemask Bottom")
		(5 "F.SilkS" user "Ref Des/Silkscreen Top")
		(7 "B.SilkS" user "Ref Des/Silkscreen Bottom")
		(1 "F.Mask" user "Board Geometry/Soldermask Top")
		(3 "B.Mask" user "Board Geometry/Soldermask Bottom")
		(17 "Dwgs.User" user "User.Drawings")
		(19 "Cmts.User" user "User.Comments")
		(21 "Eco1.User" user "User.Eco1")
		(23 "Eco2.User" user "User.Eco2")
		(25 "Edge.Cuts" user "Board Geometry/Outline")
		(27 "Margin" user)
		(31 "F.CrtYd" user "Package Geometry/Place Bound Top")
		(29 "B.CrtYd" user "Package Geometry/Place Bound Bottom")
		(35 "F.Fab" user "Ref Des/Assembly Top")
		(33 "B.Fab" user "Ref Des/Assembly Bottom")
	)
	(footprint ""
		(layer "F.Cu")
		(at 364.50143 -251.375418 90)
		(property "Reference" "C1032"
			(at 0 0 90)
			(layer "F.SilkS")
			(hide yes)
			(effects
				(font
					(size 1.27 1.27)
				)
			)
		)
		(property "Value" ""
			(at 0 0 90)
			(layer "F.Fab")
			(effects
				(font
					(size 1.27 1.27)
				)
			)
		)
		(duplicate_pad_numbers_are_jumpers no)
		(fp_line
			(start 0.7874 -0.4064)
			(end 0.7874 0.4064)
			(stroke
				(width 0.1524)
				(type default)
			)
			(layer "F.SilkS")
		)
		(fp_line
			(start -0.7874 -0.4064)
			(end 0.7874 -0.4064)
			(stroke
				(width 0.1524)
				(type default)
			)
			(layer "F.SilkS")
		)
		(fp_line
			(start 0.7874 0.4064)
			(end -0.7874 0.4064)
			(stroke
				(width 0.1524)
				(type default)
			)
			(layer "F.SilkS")
		)
		(fp_line
			(start -0.7874 0.4064)
			(end -0.7874 -0.4064)
			(stroke
				(width 0.1524)
				(type default)
			)
			(layer "F.SilkS")
		)
		(fp_line
			(start -0.12065 -0.305054)
			(end -0.12065 -0.2794)
			(stroke
				(width 0.1)
				(type default)
			)
			(layer "F.Fab")
		)
		(fp_line
			(start -0.67945 -0.305054)
			(end -0.12065 -0.305054)
			(stroke
				(width 0.1)
				(type default)
			)
			(layer "F.Fab")
		)
		(fp_line
			(start 0.67945 -0.3048)
			(end 0.67945 0.3048)
			(stroke
				(width 0.1)
				(type default)
			)
			(layer "F.Fab")
		)
		(fp_line
			(start 0.12065 -0.3048)
			(end 0.67945 -0.3048)
			(stroke
				(width 0.1)
				(type default)
			)
			(layer "F.Fab")
		)
		(fp_line
			(start 0.12065 -0.2794)
			(end 0.12065 -0.3048)
			(stroke
				(width 0.1)
				(type default)
			)
			(layer "F.Fab")
		)
		(fp_line
			(start -0.12065 -0.2794)
			(end 0.12065 -0.2794)
			(stroke
				(width 0.1)
				(type default)
			)
			(layer "F.Fab")
		)
		(fp_line
			(start 0.120396 0.2794)
			(end -0.12065 0.2794)
			(stroke
				(width 0.1)
				(type default)
			)
			(layer "F.Fab")
		)
		(fp_line
			(start -0.12065 0.2794)
			(end -0.12065 0.3048)
			(stroke
				(width 0.1)
				(type default)
			)
			(layer "F.Fab")
		)
		(fp_line
			(start 0.67945 0.3048)
			(end 0.120396 0.3048)
			(stroke
				(width 0.1)
				(type default)
			)
			(layer "F.Fab")
		)
		(fp_line
			(start 0.120396 0.3048)
			(end 0.120396 0.2794)
			(stroke
				(width 0.1)
				(type default)
			)
			(layer "F.Fab")
		)
		(fp_line
			(start -0.12065 0.3048)
			(end -0.67945 0.3048)
			(stroke
				(width 0.1)
				(type default)
			)
			(layer "F.Fab")
		)
		(fp_line
			(start -0.67945 0.3048)
			(end -0.67945 -0.305054)
			(stroke
				(width 0.1)
				(type default)
			)
			(layer "F.Fab")
		)
		(pad "1" smd circle
			(at -0.40005 0 90)
			(size 0 0)
			(layers "F.Cu" "F.Mask" "F.Paste")
			(net "PVCCIN_CPU0")
		)
		(pad "2" smd circle
			(at 0.40005 0 90)
			(size 0 0)
			(layers "F.Cu" "F.Mask" "F.Paste")
			(net "GND")
		)
	)
	(footprint ""
		(layer "F.Cu")
		(at 174.90948 -424.398948)
		(property "Reference" "C1769"
			(at 0 0 0)
			(layer "F.SilkS")
			(hide yes)
			(effects
				(font
					(size 1.27 1.27)
				)
			)
		)
		(property "Value" ""
			(at 0 0 0)
			(layer "F.Fab")
			(effects
				(font
					(size 1.27 1.27)
				)
			)
		)
		(duplicate_pad_numbers_are_jumpers no)
		(fp_line
			(start -0.7874 -0.4064)
			(end 0.7874 -0.4064)
			(stroke
				(width 0.1524)
				(type default)
			)
			(layer "F.SilkS")
		)
		(fp_line
			(start -0.7874 0.4064)
			(end -0.7874 -0.4064)
			(stroke
				(width 0.1524)
				(type default)
			)
			(layer "F.SilkS")
		)
		(fp_line
			(start 0.7874 -0.4064)
			(end 0.7874 0.4064)
			(stroke
				(width 0.1524)
				(type default)
			)
			(layer "F.SilkS")
		)
		(fp_line
			(start 0.7874 0.4064)
			(end -0.7874 0.4064)
			(stroke
				(width 0.1524)
				(type default)
			)
			(layer "F.SilkS")
		)
		(fp_line
			(start -0.67945 -0.305054)
			(end -0.12065 -0.305054)
			(stroke
				(width 0.1)
				(type default)
			)
			(layer "F.Fab")
		)
		(fp_line
			(start -0.67945 0.3048)
			(end -0.67945 -0.305054)
			(stroke
				(width 0.1)
				(type default)
			)
			(layer "F.Fab")
		)
		(fp_line
			(start -0.12065 -0.305054)
			(end -0.12065 -0.2794)
			(stroke
				(width 0.1)
				(type default)
			)
			(layer "F.Fab")
		)
		(fp_line
			(start -0.12065 -0.2794)
			(end 0.12065 -0.2794)
			(stroke
				(width 0.1)
				(type default)
			)
			(layer "F.Fab")
		)
		(fp_line
			(start -0.12065 0.2794)
			(end -0.12065 0.3048)
			(stroke
				(width 0.1)
				(type default)
			)
			(layer "F.Fab")
		)
		(fp_line
			(start -0.12065 0.3048)
			(end -0.67945 0.3048)
			(stroke
				(width 0.1)
				(type default)
			)
			(layer "F.Fab")
		)
		(fp_line
			(start 0.120396 0.2794)
			(end -0.12065 0.2794)
			(stroke
				(width 0.1)
				(type default)
			)
			(layer "F.Fab")
		)
		(fp_line
			(start 0.120396 0.3048)
			(end 0.120396 0.2794)
			(stroke
				(width 0.1)
				(type default)
			)
			(layer "F.Fab")
		)
		(fp_line
			(start 0.12065 -0.3048)
			(end 0.67945 -0.3048)
			(stroke
				(width 0.1)
				(type default)
			)
			(layer "F.Fab")
		)
		(fp_line
			(start 0.12065 -0.2794)
			(end 0.12065 -0.3048)
			(stroke
				(width 0.1)
				(type default)
			)
			(layer "F.Fab")
		)
		(fp_line
			(start 0.67945 -0.3048)
			(end 0.67945 0.3048)
			(stroke
				(width 0.1)
				(type default)
			)
			(layer "F.Fab")
		)
		(fp_line
			(start 0.67945 0.3048)
			(end 0.120396 0.3048)
			(stroke
				(width 0.1)
				(type default)
			)
			(layer "F.Fab")
		)
		(pad "1" smd circle
			(at -0.40005 0)
			(size 0 0)
			(layers "F.Cu" "F.Mask" "F.Paste")
			(net "P3V3_AUX")
		)
		(pad "2" smd circle
			(at 0.40005 0)
			(size 0 0)
			(layers "F.Cu" "F.Mask" "F.Paste")
			(net "GND")
		)
	)
)
